# SCM (Grand Teton) — schematic netlist excerpt (pin names and nets, part order shuffled) for the footprints in the layout excerpt that follows; sources: Cadence DE-HDL packaged netlist, KiCad conversion of 12092022_DA0F0TMDCD0_F0T_Management_Board_D_brd_V3_OCP.brd

R537  Q_RES  33.2 1% CHIP  pkg 0402LF  page 35 : A = BMC_CPLD_GPIO_13_R2 ; B = BMC_CPLD_GPIO_13
PC239  Q_CAP  100PF 50V 5% NPO  pkg 0402  page 52 : A = P3V3_AUX_FB_RC ; B = P3V3_AUX

(kicad_pcb
	(version 20260206)
	(generator "pcbnew")
	(generator_version "10.0")
	(general
		(thickness 1.6)
		(legacy_teardrops no)
	)
	(paper "A4")
	(title_block
		(title "12092022_DA0F0TMDCD0_F0T_Management_Board_D_brd_V3_OCP.brd")
		(comment 1 "Grand Teton / footprints 57-58 of 1440")
	)
	(layers
		(0 "F.Cu" signal "TOP")
		(4 "In1.Cu" signal "GND")
		(6 "In2.Cu" signal "IN1")
		(8 "In3.Cu" signal "GND1")
		(10 "In4.Cu" signal "IN2")
		(12 "In5.Cu" signal "VCC")
		(14 "In6.Cu" signal "VCC1")
		(16 "In7.Cu" signal "IN3")
		(18 "In8.Cu" signal "GND2")
		(20 "In9.Cu" signal "IN4")
		(22 "In10.Cu" signal "GND3")
		(2 "B.Cu" signal "BOTTOM")
		(9 "F.Adhes" user "F.Adhesive")
		(11 "B.Adhes" user "B.Adhesive")
		(13 "F.Paste" user "Package Geometry/Pastemask Top")
		(15 "B.Paste" user "Package Geometry/Pastemask Bottom")
		(5 "F.SilkS" user "Ref Des/Silkscreen Top")
		(7 "B.SilkS" user "Ref Des/Silkscreen Bottom")
		(1 "F.Mask" user "Board Geometry/Soldermask Top")
		(3 "B.Mask" user "Board Geometry/Soldermask Bottom")
		(17 "Dwgs.User" user "User.Drawings")
		(19 "Cmts.User" user "User.Comments")
		(21 "Eco1.User" user "User.Eco1")
		(23 "Eco2.User" user "User.Eco2")
		(25 "Edge.Cuts" user "Board Geometry/Outline")
		(27 "Margin" user)
		(31 "F.CrtYd" user "Package Geometry/Place Bound Top")
		(29 "B.CrtYd" user "Package Geometry/Place Bound Bottom")
		(35 "F.Fab" user "Ref Des/Assembly Top")
		(33 "B.Fab" user "Ref Des/Assembly Bottom")
	)
	(footprint ""
		(layer "F.Cu")
		(at 12.319 -95.504 180)
		(property "Reference" "R537"
			(at 0 0 180)
			(layer "F.SilkS")
			(hide yes)
			(effects
				(font
					(size 1.27 1.27)
				)
			)
		)
		(property "Value" ""
			(at 0 0 180)
			(layer "F.Fab")
			(effects
				(font
					(size 1.27 1.27)
				)
			)
		)
		(duplicate_pad_numbers_are_jumpers no)
		(fp_line
			(start 0.7874 0.4064)
			(end -0.7874 0.4064)
			(stroke
				(width 0.1524)
				(type default)
			)
			(layer "F.SilkS")
		)
		(fp_line
			(start 0.7874 -0.4064)
			(end 0.7874 0.4064)
			(stroke
				(width 0.1524)
				(type default)
			)
			(layer "F.SilkS")
		)
		(fp_line
			(start -0.7874 0.4064)
			(end -0.7874 -0.4064)
			(stroke
				(width 0.1524)
				(type default)
			)
			(layer "F.SilkS")
		)
		(fp_line
			(start -0.7874 -0.4064)
			(end 0.7874 -0.4064)
			(stroke
				(width 0.1524)
				(type default)
			)
			(layer "F.SilkS")
		)
		(fp_line
			(start 0.67945 0.3048)
			(end 0.120396 0.3048)
			(stroke
				(width 0.1)
				(type default)
			)
			(layer "F.Fab")
		)
		(fp_line
			(start 0.67945 -0.3048)
			(end 0.67945 0.3048)
			(stroke
				(width 0.1)
				(type default)
			)
			(layer "F.Fab")
		)
		(fp_line
			(start 0.12065 -0.2794)
			(end 0.12065 -0.3048)
			(stroke
				(width 0.1)
				(type default)
			)
			(layer "F.Fab")
		)
		(fp_line
			(start 0.12065 -0.3048)
			(end 0.67945 -0.3048)
			(stroke
				(width 0.1)
				(type default)
			)
			(layer "F.Fab")
		)
		(fp_line
			(start 0.120396 0.3048)
			(end 0.120396 0.2794)
			(stroke
				(width 0.1)
				(type default)
			)
			(layer "F.Fab")
		)
		(fp_line
			(start 0.120396 0.2794)
			(end -0.12065 0.2794)
			(stroke
				(width 0.1)
				(type default)
			)
			(layer "F.Fab")
		)
		(fp_line
			(start -0.12065 0.3048)
			(end -0.67945 0.3048)
			(stroke
				(width 0.1)
				(type default)
			)
			(layer "F.Fab")
		)
		(fp_line
			(start -0.12065 0.2794)
			(end -0.12065 0.3048)
			(stroke
				(width 0.1)
				(type default)
			)
			(layer "F.Fab")
		)
		(fp_line
			(start -0.12065 -0.2794)
			(end 0.12065 -0.2794)
			(stroke
				(width 0.1)
				(type default)
			)
			(layer "F.Fab")
		)
		(fp_line
			(start -0.12065 -0.305054)
			(end -0.12065 -0.2794)
			(stroke
				(width 0.1)
				(type default)
			)
			(layer "F.Fab")
		)
		(fp_line
			(start -0.67945 0.3048)
			(end -0.67945 -0.305054)
			(stroke
				(width 0.1)
				(type default)
			)
			(layer "F.Fab")
		)
		(fp_line
			(start -0.67945 -0.305054)
			(end -0.12065 -0.305054)
			(stroke
				(width 0.1)
				(type default)
			)
			(layer "F.Fab")
		)
		(pad "1" smd circle
			(at -0.40005 0 180)
			(size 0 0)
			(layers "F.Cu" "F.Mask" "F.Paste")
			(net "BMC_CPLD_GPIO_13_R2")
		)
		(pad "2" smd circle
			(at 0.40005 0 180)
			(size 0 0)
			(layers "F.Cu" "F.Mask" "F.Paste")
			(net "BMC_CPLD_GPIO_13")
		)
	)
	(footprint ""
		(layer "F.Cu")
		(at 12.30376 -64.54394 90)
		(property "Reference" "PC239"
			(at 0 0 90)
			(layer "F.SilkS")
			(hide yes)
			(effects
				(font
					(size 1.27 1.27)
				)
			)
		)
		(property "Value" ""
			(at 0 0 90)
			(layer "F.Fab")
			(effects
				(font
					(size 1.27 1.27)
				)
			)
		)
		(duplicate_pad_numbers_are_jumpers no)
		(fp_line
			(start 0.7874 -0.4064)
			(end 0.7874 0.4064)
			(stroke
				(width 0.1524)
				(type default)
			)
			(layer "F.SilkS")
		)
		(fp_line
			(start -0.7874 -0.4064)
			(end 0.7874 -0.4064)
			(stroke
				(width 0.1524)
				(type default)
			)
			(layer "F.SilkS")
		)
		(fp_line
			(start 0.7874 0.4064)
			(end -0.7874 0.4064)
			(stroke
				(width 0.1524)
				(type default)
			)
			(layer "F.SilkS")
		)
		(fp_line
			(start -0.7874 0.4064)
			(end -0.7874 -0.4064)
			(stroke
				(width 0.1524)
				(type default)
			)
			(layer "F.SilkS")
		)
		(fp_line
			(start -0.12065 -0.305054)
			(end -0.12065 -0.2794)
			(stroke
				(width 0.1)
				(type default)
			)
			(layer "F.Fab")
		)
		(fp_line
			(start -0.67945 -0.305054)
			(end -0.12065 -0.305054)
			(stroke
				(width 0.1)
				(type default)
			)
			(layer "F.Fab")
		)
		(fp_line
			(start 0.67945 -0.3048)
			(end 0.67945 0.3048)
			(stroke
				(width 0.1)
				(type default)
			)
			(layer "F.Fab")
		)
		(fp_line
			(start 0.12065 -0.3048)
			(end 0.67945 -0.3048)
			(stroke
				(width 0.1)
				(type default)
			)
			(layer "F.Fab")
		)
		(fp_line
			(start 0.12065 -0.2794)
			(end 0.12065 -0.3048)
			(stroke
				(width 0.1)
				(type default)
			)
			(layer "F.Fab")
		)
		(fp_line
			(start -0.12065 -0.2794)
			(end 0.12065 -0.2794)
			(stroke
				(width 0.1)
				(type default)
			)
			(layer "F.Fab")
		)
		(fp_line
			(start 0.120396 0.2794)
			(end -0.12065 0.2794)
			(stroke
				(width 0.1)
				(type default)
			)
			(layer "F.Fab")
		)
		(fp_line
			(start -0.12065 0.2794)
			(end -0.12065 0.3048)
			(stroke
				(width 0.1)
				(type default)
			)
			(layer "F.Fab")
		)
		(fp_line
			(start 0.67945 0.3048)
			(end 0.120396 0.3048)
			(stroke
				(width 0.1)
				(type default)
			)
			(layer "F.Fab")
		)
		(fp_line
			(start 0.120396 0.3048)
			(end 0.120396 0.2794)
			(stroke
				(width 0.1)
				(type default)
			)
			(layer "F.Fab")
		)
		(fp_line
			(start -0.12065 0.3048)
			(end -0.67945 0.3048)
			(stroke
				(width 0.1)
				(type default)
			)
			(layer "F.Fab")
		)
		(fp_line
			(start -0.67945 0.3048)
			(end -0.67945 -0.305054)
			(stroke
				(width 0.1)
				(type default)
			)
			(layer "F.Fab")
		)
		(pad "1" smd circle
			(at -0.40005 0 90)
			(size 0 0)
			(layers "F.Cu" "F.Mask" "F.Paste")
			(net "P3V3_AUX_FB_RC")
		)
		(pad "2" smd circle
			(at 0.40005 0 90)
			(size 0 0)
			(layers "F.Cu" "F.Mask" "F.Paste")
			(net "P3V3_AUX")
		)
	)
)
